# TIMECARD (Time Appliance Project (Time Card)) — schematic netlist excerpt (pin names and nets, part order shuffled) for the footprints in the layout excerpt that follows; sources: Cadence DE-HDL packaged netlist, KiCad conversion of R4006-B0001-02_R01.brd

TP13  TP_PIONT  pkg TP010CT020B030_PTH  page 25 : \1\ = MUX2_SEL
C197  CAPACITOR  0.1UF 25V 10%  pkg SMC_0402R_H022  page 30 : \1\ = XP1R8V_FPGA ; \2\ = SG
R113  RESISTOR  33OHM 1%  pkg SMC_0402R_H016  page 22 : \1\ = DBG_UART_GPS_RXD ; \2\ = GPS_UART_RXD

(kicad_pcb
	(version 20260206)
	(generator "pcbnew")
	(generator_version "10.0")
	(general
		(thickness 1.6)
		(legacy_teardrops no)
	)
	(paper "A4")
	(title_block
		(title "timecard-production-celestica-r4006 — R4006-B0001-02_R01.brd")
		(comment 1 "Time Appliance Project (Time Card) / footprints 109-111 of 1113")
	)
	(layers
		(0 "F.Cu" signal "TOP")
		(4 "In1.Cu" signal "L02_GND1")
		(6 "In2.Cu" signal "L03_SIG1")
		(8 "In3.Cu" signal "L04_GND2")
		(10 "In4.Cu" signal "L05_VCC1")
		(12 "In5.Cu" signal "L06_VCC2")
		(14 "In6.Cu" signal "L07_GND3")
		(16 "In7.Cu" signal "L08_SIG2")
		(18 "In8.Cu" signal "L09_GND4")
		(2 "B.Cu" signal "BOTTOM")
		(9 "F.Adhes" user "F.Adhesive")
		(11 "B.Adhes" user "B.Adhesive")
		(13 "F.Paste" user "Package Geometry/Pastemask Top")
		(15 "B.Paste" user "Package Geometry/Pastemask Bottom")
		(5 "F.SilkS" user "Ref Des/Silkscreen Top")
		(7 "B.SilkS" user "Ref Des/Silkscreen Bottom")
		(1 "F.Mask" user "Board Geometry/Soldermask Top")
		(3 "B.Mask" user "Board Geometry/Soldermask Bottom")
		(17 "Dwgs.User" user "User.Drawings")
		(19 "Cmts.User" user "User.Comments")
		(21 "Eco1.User" user "User.Eco1")
		(23 "Eco2.User" user "User.Eco2")
		(25 "Edge.Cuts" user "Board Geometry/Outline")
		(27 "Margin" user)
		(31 "F.CrtYd" user "Package Geometry/Place Bound Top")
		(29 "B.CrtYd" user "Package Geometry/Place Bound Bottom")
		(35 "F.Fab" user "Ref Des/Assembly Top")
		(33 "B.Fab" user "Ref Des/Assembly Bottom")
	)
	(footprint ""
		(layer "F.Cu")
		(at 131.6482 -65.8368 180)
		(property "Reference" "C197"
			(at -0.635 -4.10337 0)
			(unlocked yes)
			(layer "F.SilkS")
			(effects
				(font
					(size 0.7874 0.5842)
					(thickness 0.1524)
				)
			)
		)
		(property "Value" "VAL*"
			(at 0.0762 2.067306 180)
			(unlocked yes)
			(layer "F.Fab")
			(hide yes)
			(effects
				(font
					(size 0.7874 0.5842)
					(thickness 0.1524)
				)
			)
		)
		(property "Device Type" "CAPACITOR-G105-0B104-EK,0.1UF,A"
			(at 0.0508 1.127506 180)
			(unlocked yes)
			(layer "F.Fab")
			(hide yes)
			(effects
				(font
					(size 0.7874 0.5842)
					(thickness 0.1524)
				)
			)
		)
		(property "User Part Number" "PARTNUM*"
			(at 0.1016 4.023106 180)
			(unlocked yes)
			(layer "Cmts.User")
			(hide yes)
			(effects
				(font
					(size 0.7874 0.5842)
					(thickness 0.1524)
				)
			)
		)
		(property "Tolerance" "TOL*"
			(at 0.0762 3.032506 180)
			(unlocked yes)
			(layer "Cmts.User")
			(hide yes)
			(effects
				(font
					(size 0.7874 0.5842)
					(thickness 0.1524)
				)
			)
		)
		(duplicate_pad_numbers_are_jumpers no)
		(fp_line
			(start 1.143 0.5588)
			(end 1.143 -0.5588)
			(stroke
				(width 0.1)
				(type default)
			)
			(layer "F.SilkS")
		)
		(fp_line
			(start 1.143 -0.5588)
			(end -1.143 -0.5588)
			(stroke
				(width 0.1)
				(type default)
			)
			(layer "F.SilkS")
		)
		(fp_line
			(start -1.143 0.5588)
			(end 1.143 0.5588)
			(stroke
				(width 0.1)
				(type default)
			)
			(layer "F.SilkS")
		)
		(fp_line
			(start -1.143 -0.5588)
			(end -1.143 0.5588)
			(stroke
				(width 0.1)
				(type default)
			)
			(layer "F.SilkS")
		)
		(fp_rect
			(start -1.143 0.5588)
			(end 1.143 -0.5588)
			(stroke
				(width 0)
				(type default)
			)
			(fill no)
			(layer "F.CrtYd")
		)
		(fp_line
			(start 0.508 0.3048)
			(end 0.508 -0.3048)
			(stroke
				(width 0.1)
				(type default)
			)
			(layer "F.Fab")
		)
		(fp_line
			(start 0.508 -0.3048)
			(end -0.508 -0.3048)
			(stroke
				(width 0.1)
				(type default)
			)
			(layer "F.Fab")
		)
		(fp_line
			(start -0.508 0.3048)
			(end 0.508 0.3048)
			(stroke
				(width 0.1)
				(type default)
			)
			(layer "F.Fab")
		)
		(fp_line
			(start -0.508 -0.3048)
			(end -0.508 0.3048)
			(stroke
				(width 0.1)
				(type default)
			)
			(layer "F.Fab")
		)
		(pad "1" smd rect
			(at -0.5334 0 180)
			(size 0.7112 0.6096)
			(layers "F.Cu" "F.Mask" "F.Paste")
			(net "XP1R8V_FPGA")
		)
		(pad "2" smd rect
			(at 0.5334 0 180)
			(size 0.7112 0.6096)
			(layers "F.Cu" "F.Mask" "F.Paste")
			(net "SG")
		)
		(zone
			(layer "F.Cu")
			(hatch none 0.5)
			(connect_pads
				(clearance 0)
			)
			(min_thickness 0.25)
			(keepout
				(tracks allowed)
				(vias not_allowed)
				(pads allowed)
				(copperpour not_allowed)
				(footprints allowed)
			)
			(placement
				(enabled no)
				(sheetname "")
			)
			(fill
				(thermal_gap 0.5)
				(thermal_bridge_width 0.5)
				(island_removal_mode 0)
			)
			(polygon
				(pts
					(xy 131.7244 -66.1416) (xy 131.572 -66.1416) (xy 131.572 -65.532) (xy 131.7244 -65.532)
				)
			)
		)
	)
	(footprint ""
		(layer "F.Cu")
		(at 103.632 -83.058)
		(property "Reference" "TP13"
			(at -0.7112 -1.35763 0)
			(unlocked yes)
			(layer "F.SilkS")
			(effects
				(font
					(size 0.7874 0.5842)
					(thickness 0.1524)
				)
				(justify left)
			)
		)
		(property "Value" ""
			(at 0 0 0)
			(layer "F.Fab")
			(effects
				(font
					(size 1.27 1.27)
				)
			)
		)
		(property "Device Type" "TP_PIONT-TP010CT020B030_PTH-TPA"
			(at -1.341882 0.996696 0)
			(unlocked yes)
			(layer "F.Fab")
			(hide yes)
			(effects
				(font
					(size 0.7874 0.5842)
					(thickness 0.000001)
				)
				(justify left)
			)
		)
		(duplicate_pad_numbers_are_jumpers no)
		(fp_poly
			(pts
				(arc
					(start 0.889 0)
					(mid -0.889 0)
					(end 0.889 0)
				)
			)
			(stroke
				(width 0)
				(type default)
			)
			(fill no)
			(layer "B.CrtYd")
		)
		(fp_poly
			(pts
				(arc
					(start 0.889 0)
					(mid -0.889 0)
					(end 0.889 0)
				)
			)
			(stroke
				(width 0)
				(type default)
			)
			(fill no)
			(layer "F.CrtYd")
		)
		(pad "1" thru_hole circle
			(at 0 0)
			(size 0.508 0.508)
			(drill 0.254)
			(layers "*.Cu" "*.Mask")
			(remove_unused_layers no)
			(net "MUX2_SEL")
			(clearance 0.1016)
			(padstack
				(mode front_inner_back)
				(layer "Inner"
					(shape circle)
					(size 0.508 0.508)
					(clearance 0.1016)
				)
				(layer "B.Cu"
					(shape circle)
					(size 0.762 0.762)
					(clearance -0.0254)
				)
			)
		)
	)
	(footprint ""
		(layer "F.Cu")
		(at 124.079 -89.535 90)
		(property "Reference" "R113"
			(at -3.429 0.16637 90)
			(unlocked yes)
			(layer "F.SilkS")
			(effects
				(font
					(size 0.7874 0.5842)
					(thickness 0.1524)
				)
			)
		)
		(property "Value" "VAL*"
			(at 0.02032 2.13233 90)
			(unlocked yes)
			(layer "F.Fab")
			(hide yes)
			(effects
				(font
					(size 0.7874 0.5842)
					(thickness 0.1524)
				)
			)
		)
		(property "Tolerance" "TOL*"
			(at 0.044704 3.05435 90)
			(unlocked yes)
			(layer "Cmts.User")
			(hide yes)
			(effects
				(font
					(size 0.7874 0.5842)
					(thickness 0.1524)
				)
			)
		)
		(property "User Part Number" "PARTNUM*"
			(at 0.02032 4.024884 90)
			(unlocked yes)
			(layer "Cmts.User")
			(hide yes)
			(effects
				(font
					(size 0.7874 0.5842)
					(thickness 0.1524)
				)
			)
		)
		(property "Device Type" "RESISTOR-G155-133R0-01,33OHM,1%"
			(at 0.008382 1.210564 90)
			(unlocked yes)
			(layer "F.Fab")
			(hide yes)
			(effects
				(font
					(size 0.7874 0.5842)
					(thickness 0.1524)
				)
			)
		)
		(duplicate_pad_numbers_are_jumpers no)
		(fp_line
			(start 1.143 -0.5588)
			(end -1.143 -0.5588)
			(stroke
				(width 0.1)
				(type default)
			)
			(layer "F.SilkS")
		)
		(fp_line
			(start -1.143 -0.5588)
			(end -1.143 0.5588)
			(stroke
				(width 0.1)
				(type default)
			)
			(layer "F.SilkS")
		)
		(fp_line
			(start 1.143 0.5588)
			(end 1.143 -0.5588)
			(stroke
				(width 0.1)
				(type default)
			)
			(layer "F.SilkS")
		)
		(fp_line
			(start -1.143 0.5588)
			(end 1.143 0.5588)
			(stroke
				(width 0.1)
				(type default)
			)
			(layer "F.SilkS")
		)
		(fp_rect
			(start 1.143 -0.5588)
			(end -1.143 0.5588)
			(stroke
				(width 0)
				(type default)
			)
			(fill no)
			(layer "F.CrtYd")
		)
		(fp_line
			(start 0.508 -0.3048)
			(end -0.508 -0.3048)
			(stroke
				(width 0.1)
				(type default)
			)
			(layer "F.Fab")
		)
		(fp_line
			(start -0.508 -0.3048)
			(end -0.508 0.3048)
			(stroke
				(width 0.1)
				(type default)
			)
			(layer "F.Fab")
		)
		(fp_line
			(start 0.508 0.3048)
			(end 0.508 -0.3048)
			(stroke
				(width 0.1)
				(type default)
			)
			(layer "F.Fab")
		)
		(fp_line
			(start -0.508 0.3048)
			(end 0.508 0.3048)
			(stroke
				(width 0.1)
				(type default)
			)
			(layer "F.Fab")
		)
		(pad "1" smd rect
			(at -0.5334 0 90)
			(size 0.7112 0.6096)
			(layers "F.Cu" "F.Mask" "F.Paste")
			(net "DBG_UART_GPS_RXD")
		)
		(pad "2" smd rect
			(at 0.5334 0 90)
			(size 0.7112 0.6096)
			(layers "F.Cu" "F.Mask" "F.Paste")
			(net "GPS_UART_RXD")
		)
		(zone
			(layer "F.Cu")
			(hatch none 0.5)
			(connect_pads
				(clearance 0)
			)
			(min_thickness 0.25)
			(keepout
				(tracks allowed)
				(vias not_allowed)
				(pads allowed)
				(copperpour not_allowed)
				(footprints allowed)
			)
			(placement
				(enabled no)
				(sheetname "")
			)
			(fill
				(thermal_gap 0.5)
				(thermal_bridge_width 0.5)
				(island_removal_mode 0)
			)
			(polygon
				(pts
					(xy 123.7742 -89.6112) (xy 123.7742 -89.4588) (xy 124.3838 -89.4588) (xy 124.3838 -89.6112)
				)
			)
		)
	)
)
